(kicad_pcb
	(version 20241229)
	(generator "pcbnew")
	(generator_version "9.0")
	(general
		(thickness 1.61)
		(legacy_teardrops no)
	)
	(paper "A3")
	(title_block
		(title "RDIMM DDR5 Tester")
		(date "2026-05-21")
		(rev "2.2.0")
		(company "Antmicro")
		(comment 9 "footprints 499-503 of 796")
	)
	(layers
		(0 "F.Cu" signal)
		(4 "In1.Cu" power)
		(6 "In2.Cu" mixed)
		(8 "In3.Cu" power)
		(10 "In4.Cu" mixed)
		(12 "In5.Cu" power)
		(14 "In6.Cu" mixed)
		(16 "In7.Cu" power)
		(18 "In8.Cu" power)
		(20 "In9.Cu" mixed)
		(22 "In10.Cu" power)
		(2 "B.Cu" signal)
		(9 "F.Adhes" user "F.Adhesive")
		(11 "B.Adhes" user "B.Adhesive")
		(13 "F.Paste" user)
		(15 "B.Paste" user)
		(5 "F.SilkS" user "F.Silkscreen")
		(7 "B.SilkS" user "B.Silkscreen")
		(1 "F.Mask" user)
		(3 "B.Mask" user)
		(17 "Dwgs.User" user "User.Drawings")
		(19 "Cmts.User" user "User.Comments")
		(21 "Eco1.User" user "User.Eco1")
		(23 "Eco2.User" user "User.Eco2")
		(25 "Edge.Cuts" user)
		(27 "Margin" user)
		(31 "F.CrtYd" user "F.Courtyard")
		(29 "B.CrtYd" user "B.Courtyard")
		(35 "F.Fab" user)
		(33 "B.Fab" user)
	)
	(footprint "antmicro-footprints:C_0402_1005Metric"
		(layer "B.Cu")
		(at 183.49 167.45 90)
		(descr "Capacitor SMD 0402")
		(tags "capacitor SMD 0402")
		(property "Reference" "C293"
			(at -4 0.115999 90)
			(layer "B.SilkS")
			(effects
				(font
					(size 0.7 0.7)
					(thickness 0.15)
				)
				(justify right bottom mirror)
			)
		)
		(property "Value" "C_100n_0402"
			(at -1.022927 -2.155213 90)
			(layer "B.Fab")
			(effects
				(font
					(size 0.7 0.7)
					(thickness 0.15)
				)
				(justify right bottom mirror)
			)
		)
		(property "Datasheet" "https://www.murata.com/products/productdetail?partno=GRM155R61H104KE14%23"
			(at 0 0 90)
			(layer "F.Fab")
			(hide yes)
			(effects
				(font
					(size 1.27 1.27)
					(thickness 0.15)
				)
			)
		)
		(property "Manufacturer" "Murata"
			(at 0 0 90)
			(unlocked yes)
			(layer "B.Fab")
			(hide yes)
			(effects
				(font
					(size 1 1)
					(thickness 0.15)
				)
				(justify mirror)
			)
		)
		(property "MPN" "GRM155R61H104KE14D"
			(at 0 0 90)
			(unlocked yes)
			(layer "B.Fab")
			(hide yes)
			(effects
				(font
					(size 1 1)
					(thickness 0.15)
				)
				(justify mirror)
			)
		)
		(property "Val" "100n"
			(at 0 0 90)
			(unlocked yes)
			(layer "B.Fab")
			(hide yes)
			(effects
				(font
					(size 1 1)
					(thickness 0.15)
				)
				(justify mirror)
			)
		)
		(property "License" "Apache-2.0"
			(at 0 0 90)
			(unlocked yes)
			(layer "B.Fab")
			(hide yes)
			(effects
				(font
					(size 1 1)
					(thickness 0.15)
				)
				(justify mirror)
			)
		)
		(property "Author" "Antmicro"
			(at 0 0 90)
			(unlocked yes)
			(layer "B.Fab")
			(hide yes)
			(effects
				(font
					(size 1 1)
					(thickness 0.15)
				)
				(justify mirror)
			)
		)
		(property "Voltage" "50V"
			(at 0 0 90)
			(unlocked yes)
			(layer "B.Fab")
			(hide yes)
			(effects
				(font
					(size 1 1)
					(thickness 0.15)
				)
				(justify mirror)
			)
		)
		(property "Dielectric" "X5R"
			(at 0 0 90)
			(unlocked yes)
			(layer "B.Fab")
			(hide yes)
			(effects
				(font
					(size 1 1)
					(thickness 0.15)
				)
				(justify mirror)
			)
		)
		(sheetname "/FPGA MGT Interface/")
		(sheetfile "fpga-mgt.kicad_sch")
		(attr smd)
		(fp_rect
			(start -0.925 0.47)
			(end 0.925 -0.47)
			(stroke
				(width 0.05)
				(type default)
			)
			(fill no)
			(layer "B.CrtYd")
		)
		(fp_line
			(start 0.504 -0.248)
			(end -0.494 -0.248)
			(stroke
				(width 0.15)
				(type solid)
			)
			(layer "B.Fab")
		)
		(fp_line
			(start -0.494 -0.248)
			(end -0.494 0.25)
			(stroke
				(width 0.15)
				(type solid)
			)
			(layer "B.Fab")
		)
		(fp_line
			(start 0.504 0.25)
			(end 0.504 -0.248)
			(stroke
				(width 0.15)
				(type solid)
			)
			(layer "B.Fab")
		)
		(fp_line
			(start -0.494 0.25)
			(end 0.504 0.25)
			(stroke
				(width 0.15)
				(type solid)
			)
			(layer "B.Fab")
		)
		(fp_text user "${REFERENCE}"
			(at -0.939 -4.599 270)
			(layer "B.Fab")
			(effects
				(font
					(size 0.7 0.7)
					(thickness 0.15)
				)
				(justify left bottom mirror)
			)
		)
		(fp_text user "Author: Antmicro"
			(at -0.939 -3.399 270)
			(layer "B.Fab")
			(effects
				(font
					(size 0.7 0.7)
					(thickness 0.15)
				)
				(justify left bottom mirror)
			)
		)
		(fp_text user "License: Apache-2.0"
			(at -0.939 -5.799 270)
			(layer "B.Fab")
			(effects
				(font
					(size 0.7 0.7)
					(thickness 0.15)
				)
				(justify left bottom mirror)
			)
		)
		(pad "1" smd roundrect
			(at -0.48 0 90)
			(size 0.59 0.64)
			(layers "B.Cu" "B.Mask" "B.Paste")
			(roundrect_rratio 0.25)
			(net 295 "/FPGA MGT Interface/HDMI_OUT.D2_N")
			(pintype "passive")
		)
		(pad "2" smd roundrect
			(at 0.48 0 90)
			(size 0.59 0.64)
			(layers "B.Cu" "B.Mask" "B.Paste")
			(roundrect_rratio 0.25)
			(net 627 "/FPGA MGT Interface/HDMI_FPGA.TX2_N")
			(pintype "passive")
		)
	)
	(footprint "antmicro-footprints:R_0402_1005Metric"
		(layer "B.Cu")
		(at 240.12 170.425 180)
		(descr "Resistor SMD 0402")
		(tags "resistor SMD 0402")
		(property "Reference" "R210"
			(at -4.505 -0.425 0)
			(layer "B.SilkS")
			(effects
				(font
					(size 0.7 0.7)
					(thickness 0.15)
				)
				(justify left bottom mirror)
			)
		)
		(property "Value" "R_47k_0402"
			(at -1.011843 -1.772047 0)
			(layer "B.Fab")
			(effects
				(font
					(size 0.7 0.7)
					(thickness 0.15)
				)
				(justify left bottom mirror)
			)
		)
		(property "Datasheet" "https://www.bourns.com/docs/product-datasheets/cr.pdf"
			(at 0 0 180)
			(layer "F.Fab")
			(hide yes)
			(effects
				(font
					(size 1.27 1.27)
					(thickness 0.15)
				)
			)
		)
		(property "Manufacturer" "Bourns"
			(at 0 0 180)
			(unlocked yes)
			(layer "B.Fab")
			(hide yes)
			(effects
				(font
					(size 1 1)
					(thickness 0.15)
				)
				(justify mirror)
			)
		)
		(property "MPN" "CR0402-FX-4702GLF"
			(at 0 0 180)
			(unlocked yes)
			(layer "B.Fab")
			(hide yes)
			(effects
				(font
					(size 1 1)
					(thickness 0.15)
				)
				(justify mirror)
			)
		)
		(property "Val" "47k"
			(at 0 0 180)
			(unlocked yes)
			(layer "B.Fab")
			(hide yes)
			(effects
				(font
					(size 1 1)
					(thickness 0.15)
				)
				(justify mirror)
			)
		)
		(property "License" "Apache-2.0"
			(at 0 0 180)
			(unlocked yes)
			(layer "B.Fab")
			(hide yes)
			(effects
				(font
					(size 1 1)
					(thickness 0.15)
				)
				(justify mirror)
			)
		)
		(property "Author" "Antmicro"
			(at 0 0 180)
			(unlocked yes)
			(layer "B.Fab")
			(hide yes)
			(effects
				(font
					(size 1 1)
					(thickness 0.15)
				)
				(justify mirror)
			)
		)
		(property "Tolerance" "1%"
			(at 0 0 180)
			(unlocked yes)
			(layer "B.Fab")
			(hide yes)
			(effects
				(font
					(size 1 1)
					(thickness 0.15)
				)
				(justify mirror)
			)
		)
		(sheetname "/Supply/DC-DC AUX, MGT/")
		(sheetfile "dc-dc-aux-mgt.kicad_sch")
		(attr smd)
		(fp_rect
			(start -0.925 0.47)
			(end 0.925 -0.47)
			(stroke
				(width 0.05)
				(type default)
			)
			(fill no)
			(layer "B.CrtYd")
		)
		(fp_rect
			(start -0.5 0.25)
			(end 0.5 -0.25)
			(stroke
				(width 0.15)
				(type solid)
			)
			(fill no)
			(layer "B.Fab")
		)
		(fp_text user "${REFERENCE}"
			(at -0.95 -3.168 0)
			(layer "B.Fab")
			(effects
				(font
					(size 0.7 0.7)
					(thickness 0.15)
				)
				(justify left bottom mirror)
			)
		)
		(fp_text user "License: Apache-2.0"
			(at -0.95 -5.169 0)
			(layer "B.Fab")
			(effects
				(font
					(size 0.7 0.7)
					(thickness 0.15)
				)
				(justify left bottom mirror)
			)
		)
		(fp_text user "Author: Antmicro"
			(at -0.95 -4.169 0)
			(layer "B.Fab")
			(effects
				(font
					(size 0.7 0.7)
					(thickness 0.15)
				)
				(justify left bottom mirror)
			)
		)
		(pad "1" smd roundrect
			(at -0.48 0 180)
			(size 0.59 0.64)
			(layers "B.Cu" "B.Mask" "B.Paste")
			(roundrect_rratio 0.25)
			(net 731 "Net-(U25-~{ALERT})")
			(pintype "passive")
		)
		(pad "2" smd roundrect
			(at 0.48 0 180)
			(size 0.59 0.64)
			(layers "B.Cu" "B.Mask" "B.Paste")
			(roundrect_rratio 0.25)
			(net 38 "+3V3_AON")
			(pintype "passive")
		)
	)
	(footprint "antmicro-footprints:C_0402_1005Metric_EIA"
		(layer "B.Cu")
		(at 190 150.5 -90)
		(descr "Capacitor SMD 0402 (1005 Metric), square (rectangular) end terminal, IPC_7351 nominal, (Body size source: IPC-SM-782 page 76, https://www.pcb-3d.com/wordpress/wp-content/uploads/ipc-sm-782a_amendment_1_and_2.pdf)")
		(tags "capacitor 0402")
		(property "Reference" "C86"
			(at -11.975 30.675 90)
			(layer "B.SilkS")
			(effects
				(font
					(size 0.7 0.7)
					(thickness 0.15)
				)
				(justify left bottom mirror)
			)
		)
		(property "Value" "C_1u_25V_0402"
			(at 0 -1.169 90)
			(layer "B.Fab")
			(effects
				(font
					(size 0.7 0.7)
					(thickness 0.15)
				)
				(justify left bottom mirror)
			)
		)
		(property "Datasheet" "https://www.murata.com/products/productdetail?partno=GRM155R61E105KE11%23"
			(at 0 0 270)
			(layer "F.Fab")
			(hide yes)
			(effects
				(font
					(size 1.27 1.27)
					(thickness 0.15)
				)
			)
		)
		(property "MPN" "GRM155R61E105KE11J"
			(at 0 0 270)
			(unlocked yes)
			(layer "B.Fab")
			(hide yes)
			(effects
				(font
					(size 1 1)
					(thickness 0.15)
				)
				(justify mirror)
			)
		)
		(property "Manufacturer" "Murata"
			(at 0 0 270)
			(unlocked yes)
			(layer "B.Fab")
			(hide yes)
			(effects
				(font
					(size 1 1)
					(thickness 0.15)
				)
				(justify mirror)
			)
		)
		(property "License" "Apache-2.0"
			(at 0 0 270)
			(unlocked yes)
			(layer "B.Fab")
			(hide yes)
			(effects
				(font
					(size 1 1)
					(thickness 0.15)
				)
				(justify mirror)
			)
		)
		(property "Author" "Antmicro"
			(at 0 0 270)
			(unlocked yes)
			(layer "B.Fab")
			(hide yes)
			(effects
				(font
					(size 1 1)
					(thickness 0.15)
				)
				(justify mirror)
			)
		)
		(property "Val" "1u"
			(at 0 0 270)
			(unlocked yes)
			(layer "B.Fab")
			(hide yes)
			(effects
				(font
					(size 1 1)
					(thickness 0.15)
				)
				(justify mirror)
			)
		)
		(property "Voltage" "25V"
			(at 0 0 270)
			(unlocked yes)
			(layer "B.Fab")
			(hide yes)
			(effects
				(font
					(size 1 1)
					(thickness 0.15)
				)
				(justify mirror)
			)
		)
		(property "Dielectric" "X5R"
			(at 0 0 270)
			(unlocked yes)
			(layer "B.Fab")
			(hide yes)
			(effects
				(font
					(size 1 1)
					(thickness 0.15)
				)
				(justify mirror)
			)
		)
		(sheetname "/FPGA power/")
		(sheetfile "fpga-power.kicad_sch")
		(attr smd)
		(fp_rect
			(start -0.95 0.45)
			(end 0.95 -0.45)
			(stroke
				(width 0.05)
				(type default)
			)
			(fill no)
			(layer "B.CrtYd")
		)
		(fp_line
			(start -0.5 0.25)
			(end 0.498 0.25)
			(stroke
				(width 0.15)
				(type solid)
			)
			(layer "B.Fab")
		)
		(fp_line
			(start 0.498 0.25)
			(end 0.498 -0.248)
			(stroke
				(width 0.15)
				(type solid)
			)
			(layer "B.Fab")
		)
		(fp_line
			(start -0.5 -0.248)
			(end -0.5 0.25)
			(stroke
				(width 0.15)
				(type solid)
			)
			(layer "B.Fab")
		)
		(fp_line
			(start 0.498 -0.248)
			(end -0.5 -0.248)
			(stroke
				(width 0.15)
				(type solid)
			)
			(layer "B.Fab")
		)
		(fp_text user "${REFERENCE}"
			(at -0.9656 -3.169 90)
			(layer "B.Fab")
			(effects
				(font
					(size 0.7 0.7)
					(thickness 0.15)
				)
				(justify left bottom mirror)
			)
		)
		(fp_text user "Author: Antmicro"
			(at -0.9656 -5.569 90)
			(layer "B.Fab")
			(effects
				(font
					(size 0.7 0.7)
					(thickness 0.15)
				)
				(justify left bottom mirror)
			)
		)
		(fp_text user "License: Apache-2.0"
			(at -0.9656 -4.369 90)
			(layer "B.Fab")
			(effects
				(font
					(size 0.7 0.7)
					(thickness 0.15)
				)
				(justify left bottom mirror)
			)
		)
		(pad "1" smd roundrect
			(at -0.5 0 180)
			(size 0.6 0.6)
			(layers "B.Cu" "B.Mask" "B.Paste")
			(roundrect_rratio 0.25)
			(net 1 "GND")
			(pintype "passive")
		)
		(pad "2" smd roundrect
			(at 0.498 0 270)
			(size 0.6 0.6)
			(layers "B.Cu" "B.Mask" "B.Paste")
			(roundrect_rratio 0.25)
			(net 553 "+0V85")
			(pintype "passive")
		)
	)
	(footprint "antmicro-footprints:C_0402_1005Metric"
		(layer "B.Cu")
		(at 174.32 108.3 180)
		(descr "Capacitor SMD 0402")
		(tags "capacitor SMD 0402")
		(property "Reference" "C10"
			(at 1.07 -0.44 0)
			(layer "B.SilkS")
			(effects
				(font
					(size 0.7 0.7)
					(thickness 0.15)
				)
				(justify left bottom mirror)
			)
		)
		(property "Value" "C_100n_0402"
			(at -1.022927 -2.155213 0)
			(layer "B.Fab")
			(effects
				(font
					(size 0.7 0.7)
					(thickness 0.15)
				)
				(justify left bottom mirror)
			)
		)
		(property "Datasheet" "https://www.murata.com/products/productdetail?partno=GRM155R61H104KE14%23"
			(at 0 0 180)
			(layer "F.Fab")
			(hide yes)
			(effects
				(font
					(size 1.27 1.27)
					(thickness 0.15)
				)
			)
		)
		(property "MPN" "GRM155R61H104KE14D"
			(at 0 0 180)
			(unlocked yes)
			(layer "B.Fab")
			(hide yes)
			(effects
				(font
					(size 1 1)
					(thickness 0.15)
				)
				(justify mirror)
			)
		)
		(property "Manufacturer" "Murata"
			(at 0 0 180)
			(unlocked yes)
			(layer "B.Fab")
			(hide yes)
			(effects
				(font
					(size 1 1)
					(thickness 0.15)
				)
				(justify mirror)
			)
		)
		(property "License" "Apache-2.0"
			(at 0 0 180)
			(unlocked yes)
			(layer "B.Fab")
			(hide yes)
			(effects
				(font
					(size 1 1)
					(thickness 0.15)
				)
				(justify mirror)
			)
		)
		(property "Author" "Antmicro"
			(at 0 0 180)
			(unlocked yes)
			(layer "B.Fab")
			(hide yes)
			(effects
				(font
					(size 1 1)
					(thickness 0.15)
				)
				(justify mirror)
			)
		)
		(property "Val" "100n"
			(at 0 0 180)
			(unlocked yes)
			(layer "B.Fab")
			(hide yes)
			(effects
				(font
					(size 1 1)
					(thickness 0.15)
				)
				(justify mirror)
			)
		)
		(property "Voltage" "50V"
			(at 0 0 180)
			(unlocked yes)
			(layer "B.Fab")
			(hide yes)
			(effects
				(font
					(size 1 1)
					(thickness 0.15)
				)
				(justify mirror)
			)
		)
		(property "Dielectric" "X5R"
			(at 0 0 180)
			(unlocked yes)
			(layer "B.Fab")
			(hide yes)
			(effects
				(font
					(size 1 1)
					(thickness 0.15)
				)
				(justify mirror)
			)
		)
		(sheetname "/DDR5 RDIMM/")
		(sheetfile "ddr5-rdimm.kicad_sch")
		(attr smd)
		(fp_rect
			(start -0.925 0.47)
			(end 0.925 -0.47)
			(stroke
				(width 0.05)
				(type default)
			)
			(fill no)
			(layer "B.CrtYd")
		)
		(fp_line
			(start 0.504 0.25)
			(end 0.504 -0.248)
			(stroke
				(width 0.15)
				(type solid)
			)
			(layer "B.Fab")
		)
		(fp_line
			(start 0.504 -0.248)
			(end -0.494 -0.248)
			(stroke
				(width 0.15)
				(type solid)
			)
			(layer "B.Fab")
		)
		(fp_line
			(start -0.494 0.25)
			(end 0.504 0.25)
			(stroke
				(width 0.15)
				(type solid)
			)
			(layer "B.Fab")
		)
		(fp_line
			(start -0.494 -0.248)
			(end -0.494 0.25)
			(stroke
				(width 0.15)
				(type solid)
			)
			(layer "B.Fab")
		)
		(fp_text user "Author: Antmicro"
			(at -0.939 -3.399 0)
			(layer "B.Fab")
			(effects
				(font
					(size 0.7 0.7)
					(thickness 0.15)
				)
				(justify left bottom mirror)
			)
		)
		(fp_text user "${REFERENCE}"
			(at -0.939 -4.599 0)
			(layer "B.Fab")
			(effects
				(font
					(size 0.7 0.7)
					(thickness 0.15)
				)
				(justify left bottom mirror)
			)
		)
		(fp_text user "License: Apache-2.0"
			(at -0.939 -5.799 0)
			(layer "B.Fab")
			(effects
				(font
					(size 0.7 0.7)
					(thickness 0.15)
				)
				(justify left bottom mirror)
			)
		)
		(pad "1" smd roundrect
			(at -0.48 0 180)
			(size 0.59 0.64)
			(layers "B.Cu" "B.Mask" "B.Paste")
			(roundrect_rratio 0.25)
			(net 1 "GND")
			(pintype "passive")
		)
		(pad "2" smd roundrect
			(at 0.48 0 180)
			(size 0.59 0.64)
			(layers "B.Cu" "B.Mask" "B.Paste")
			(roundrect_rratio 0.25)
			(net 687 "VDDQ")
			(pintype "passive")
		)
	)
	(footprint "antmicro-footprints:R_0402_1005Metric_EIA"
		(layer "B.Cu")
		(at 196 148.499 90)
		(descr "Resistor SMD 0402 (1005 Metric), square (rectangular) end terminal, IPC_7351 nominal, (Body size source: IPC-SM-782 page 76, https://www.pcb-3d.com/wordpress/wp-content/uploads/ipc-sm-782a_amendment_1_and_2.pdf)")
		(tags "resistor 0402")
		(property "Reference" "R129"
			(at -3.901 0.4 90)
			(layer "B.SilkS")
			(effects
				(font
					(size 0.7 0.7)
					(thickness 0.15)
				)
				(justify right bottom mirror)
			)
		)
		(property "Value" "R_1k_0402"
			(at 0 -1.169 90)
			(layer "B.Fab")
			(effects
				(font
					(size 0.7 0.7)
					(thickness 0.15)
				)
				(justify right bottom mirror)
			)
		)
		(property "Datasheet" "https://www.bourns.com/docs/product-datasheets/cr.pdf"
			(at 0 0 90)
			(layer "F.Fab")
			(hide yes)
			(effects
				(font
					(size 1.27 1.27)
					(thickness 0.15)
				)
			)
		)
		(property "MPN" "CR0402-FX-1001GLF"
			(at 0 0 90)
			(unlocked yes)
			(layer "B.Fab")
			(hide yes)
			(effects
				(font
					(size 1 1)
					(thickness 0.15)
				)
				(justify mirror)
			)
		)
		(property "Manufacturer" "Bourns"
			(at 0 0 90)
			(unlocked yes)
			(layer "B.Fab")
			(hide yes)
			(effects
				(font
					(size 1 1)
					(thickness 0.15)
				)
				(justify mirror)
			)
		)
		(property "License" "Apache-2.0"
			(at 0 0 90)
			(unlocked yes)
			(layer "B.Fab")
			(hide yes)
			(effects
				(font
					(size 1 1)
					(thickness 0.15)
				)
				(justify mirror)
			)
		)
		(property "Author" "Antmicro"
			(at 0 0 90)
			(unlocked yes)
			(layer "B.Fab")
			(hide yes)
			(effects
				(font
					(size 1 1)
					(thickness 0.15)
				)
				(justify mirror)
			)
		)
		(property "Val" "1k"
			(at 0 0 90)
			(unlocked yes)
			(layer "B.Fab")
			(hide yes)
			(effects
				(font
					(size 1 1)
					(thickness 0.15)
				)
				(justify mirror)
			)
		)
		(property "Tolerance" "1%"
			(at 0 0 90)
			(unlocked yes)
			(layer "B.Fab")
			(hide yes)
			(effects
				(font
					(size 1 1)
					(thickness 0.15)
				)
				(justify mirror)
			)
		)
		(sheetname "/FPGA banks HP/")
		(sheetfile "fpga-hp-banks.kicad_sch")
		(attr smd exclude_from_bom dnp)
		(fp_rect
			(start -0.95 0.45)
			(end 0.95 -0.45)
			(stroke
				(width 0.05)
				(type default)
			)
			(fill no)
			(layer "B.CrtYd")
		)
		(fp_line
			(start 0.499 -0.249)
			(end -0.5 -0.249)
			(stroke
				(width 0.15)
				(type solid)
			)
			(layer "B.Fab")
		)
		(fp_line
			(start -0.5 -0.249)
			(end -0.5 0.25)
			(stroke
				(width 0.15)
				(type solid)
			)
			(layer "B.Fab")
		)
		(fp_line
			(start 0.499 0.25)
			(end 0.499 -0.249)
			(stroke
				(width 0.15)
				(type solid)
			)
			(layer "B.Fab")
		)
		(fp_line
			(start -0.5 0.25)
			(end 0.499 0.25)
			(stroke
				(width 0.15)
				(type solid)
			)
			(layer "B.Fab")
		)
		(fp_text user "${REFERENCE}"
			(at -0.95 -3.169 90)
			(layer "B.Fab")
			(effects
				(font
					(size 0.7 0.7)
					(thickness 0.15)
				)
				(justify right top mirror)
			)
		)
		(fp_text user "License: Apache-2.0"
			(at -0.95 -4.369 90)
			(layer "B.Fab")
			(effects
				(font
					(size 0.7 0.7)
					(thickness 0.15)
				)
				(justify right top mirror)
			)
		)
		(fp_text user "Author: Antmicro"
			(at -0.95 -5.569 90)
			(layer "B.Fab")
			(effects
				(font
					(size 0.7 0.7)
					(thickness 0.15)
				)
				(justify right top mirror)
			)
		)
		(pad "1" smd roundrect
			(at -0.5 0)
			(size 0.6 0.6)
			(layers "B.Cu" "B.Mask" "B.Paste")
			(roundrect_rratio 0.25)
			(net 1 "GND")
			(pintype "passive")
		)
		(pad "2" smd roundrect
			(at 0.499 0 90)
			(size 0.6 0.6)
			(layers "B.Cu" "B.Mask" "B.Paste")
			(roundrect_rratio 0.25)
			(net 535 "/FPGA banks HP/VREF_64")
			(pintype "passive")
		)
	)
)
